# S9S_MB_2U (Grand Teton) — schematic netlist excerpt (pin names and nets, part order shuffled) for the footprints in the layout excerpt that follows; sources: Cadence DE-HDL packaged netlist, KiCad conversion of 03242023_DA0F0TMBIJ0_F0T_Motherboard_J_brd_V01_OCP.brd

R4705  Q_RES  560 1% CHIP  pkg 0402LF  page 255 : A = LED_P12V_PSU_R2 ; B = LED_P12V_PSU_R3
R2345  Q_RES  49.9 1% EMPTY  pkg 0402LF  page 292 : A = PVNN_TERM_CPU1 ; B = SVID_CLK0_CPU1_R

(kicad_pcb
	(version 20260206)
	(generator "pcbnew")
	(generator_version "10.0")
	(general
		(thickness 1.6)
		(legacy_teardrops no)
	)
	(paper "A4")
	(title_block
		(title "03242023_DA0F0TMBIJ0_F0T_Motherboard_J_brd_V01_OCP.brd")
		(comment 1 "Grand Teton / footprints 6009-6010 of 6105")
	)
	(layers
		(0 "F.Cu" signal "TOP")
		(4 "In1.Cu" signal "GND")
		(6 "In2.Cu" signal "IN1")
		(8 "In3.Cu" signal "GND1")
		(10 "In4.Cu" signal "IN2")
		(12 "In5.Cu" signal "GND2")
		(14 "In6.Cu" signal "IN3")
		(16 "In7.Cu" signal "GND3")
		(18 "In8.Cu" signal "VCC")
		(20 "In9.Cu" signal "VCC1")
		(22 "In10.Cu" signal "GND4")
		(24 "In11.Cu" signal "IN4")
		(26 "In12.Cu" signal "GND5")
		(28 "In13.Cu" signal "IN5")
		(30 "In14.Cu" signal "GND6")
		(32 "In15.Cu" signal "IN6")
		(34 "In16.Cu" signal "GND7")
		(2 "B.Cu" signal "BOTTOM")
		(9 "F.Adhes" user "F.Adhesive")
		(11 "B.Adhes" user "B.Adhesive")
		(13 "F.Paste" user "Package Geometry/Pastemask Top")
		(15 "B.Paste" user "Package Geometry/Pastemask Bottom")
		(5 "F.SilkS" user "Ref Des/Silkscreen Top")
		(7 "B.SilkS" user "Ref Des/Silkscreen Bottom")
		(1 "F.Mask" user "Board Geometry/Soldermask Top")
		(3 "B.Mask" user "Board Geometry/Soldermask Bottom")
		(17 "Dwgs.User" user "User.Drawings")
		(19 "Cmts.User" user "User.Comments")
		(21 "Eco1.User" user "User.Eco1")
		(23 "Eco2.User" user "User.Eco2")
		(25 "Edge.Cuts" user "Board Geometry/Outline")
		(27 "Margin" user)
		(31 "F.CrtYd" user "Package Geometry/Place Bound Top")
		(29 "B.CrtYd" user "Package Geometry/Place Bound Bottom")
		(35 "F.Fab" user "Ref Des/Assembly Top")
		(33 "B.Fab" user "Ref Des/Assembly Bottom")
	)
	(footprint ""
		(layer "B.Cu")
		(at 193.71818 -423.669206 90)
		(property "Reference" "R4705"
			(at 0 0 90)
			(layer "B.SilkS")
			(hide yes)
			(effects
				(font
					(size 1.27 1.27)
				)
				(justify mirror)
			)
		)
		(property "Value" ""
			(at 0 0 90)
			(layer "B.Fab")
			(effects
				(font
					(size 1.27 1.27)
				)
				(justify mirror)
			)
		)
		(duplicate_pad_numbers_are_jumpers no)
		(fp_line
			(start 0.7874 -0.4064)
			(end -0.7874 -0.4064)
			(stroke
				(width 0.1524)
				(type default)
			)
			(layer "B.SilkS")
		)
		(fp_line
			(start -0.7874 -0.4064)
			(end -0.7874 0.4064)
			(stroke
				(width 0.1524)
				(type default)
			)
			(layer "B.SilkS")
		)
		(fp_line
			(start 0.7874 0.4064)
			(end 0.7874 -0.4064)
			(stroke
				(width 0.1524)
				(type default)
			)
			(layer "B.SilkS")
		)
		(fp_line
			(start -0.7874 0.4064)
			(end 0.7874 0.4064)
			(stroke
				(width 0.1524)
				(type default)
			)
			(layer "B.SilkS")
		)
		(fp_line
			(start 0.67945 -0.305054)
			(end 0.12065 -0.305054)
			(stroke
				(width 0.1)
				(type default)
			)
			(layer "B.Fab")
		)
		(fp_line
			(start 0.12065 -0.305054)
			(end 0.12065 -0.2794)
			(stroke
				(width 0.1)
				(type default)
			)
			(layer "B.Fab")
		)
		(fp_line
			(start -0.12065 -0.3048)
			(end -0.67945 -0.3048)
			(stroke
				(width 0.1)
				(type default)
			)
			(layer "B.Fab")
		)
		(fp_line
			(start -0.67945 -0.3048)
			(end -0.67945 0.3048)
			(stroke
				(width 0.1)
				(type default)
			)
			(layer "B.Fab")
		)
		(fp_line
			(start 0.12065 -0.2794)
			(end -0.12065 -0.2794)
			(stroke
				(width 0.1)
				(type default)
			)
			(layer "B.Fab")
		)
		(fp_line
			(start -0.12065 -0.2794)
			(end -0.12065 -0.3048)
			(stroke
				(width 0.1)
				(type default)
			)
			(layer "B.Fab")
		)
		(fp_line
			(start 0.12065 0.2794)
			(end 0.12065 0.3048)
			(stroke
				(width 0.1)
				(type default)
			)
			(layer "B.Fab")
		)
		(fp_line
			(start -0.120396 0.2794)
			(end 0.12065 0.2794)
			(stroke
				(width 0.1)
				(type default)
			)
			(layer "B.Fab")
		)
		(fp_line
			(start 0.67945 0.3048)
			(end 0.67945 -0.305054)
			(stroke
				(width 0.1)
				(type default)
			)
			(layer "B.Fab")
		)
		(fp_line
			(start 0.12065 0.3048)
			(end 0.67945 0.3048)
			(stroke
				(width 0.1)
				(type default)
			)
			(layer "B.Fab")
		)
		(fp_line
			(start -0.120396 0.3048)
			(end -0.120396 0.2794)
			(stroke
				(width 0.1)
				(type default)
			)
			(layer "B.Fab")
		)
		(fp_line
			(start -0.67945 0.3048)
			(end -0.120396 0.3048)
			(stroke
				(width 0.1)
				(type default)
			)
			(layer "B.Fab")
		)
		(pad "1" smd circle
			(at 0.40005 0 270)
			(size 0 0)
			(layers "B.Cu" "B.Mask" "B.Paste")
			(net "LED_P12V_PSU_R2")
		)
		(pad "2" smd circle
			(at -0.40005 0 270)
			(size 0 0)
			(layers "B.Cu" "B.Mask" "B.Paste")
			(net "LED_P12V_PSU_R3")
		)
	)
	(footprint ""
		(layer "B.Cu")
		(at 39.526972 -129.81813 180)
		(property "Reference" "R2345"
			(at 0 0 0)
			(layer "B.SilkS")
			(hide yes)
			(effects
				(font
					(size 1.27 1.27)
				)
				(justify mirror)
			)
		)
		(property "Value" ""
			(at 0 0 0)
			(layer "B.Fab")
			(effects
				(font
					(size 1.27 1.27)
				)
				(justify mirror)
			)
		)
		(duplicate_pad_numbers_are_jumpers no)
		(fp_line
			(start 0.7874 0.4064)
			(end 0.7874 -0.4064)
			(stroke
				(width 0.1524)
				(type default)
			)
			(layer "B.SilkS")
		)
		(fp_line
			(start 0.7874 -0.4064)
			(end -0.7874 -0.4064)
			(stroke
				(width 0.1524)
				(type default)
			)
			(layer "B.SilkS")
		)
		(fp_line
			(start -0.7874 0.4064)
			(end 0.7874 0.4064)
			(stroke
				(width 0.1524)
				(type default)
			)
			(layer "B.SilkS")
		)
		(fp_line
			(start -0.7874 -0.4064)
			(end -0.7874 0.4064)
			(stroke
				(width 0.1524)
				(type default)
			)
			(layer "B.SilkS")
		)
		(fp_line
			(start 0.67945 0.3048)
			(end 0.67945 -0.305054)
			(stroke
				(width 0.1)
				(type default)
			)
			(layer "B.Fab")
		)
		(fp_line
			(start 0.67945 -0.305054)
			(end 0.12065 -0.305054)
			(stroke
				(width 0.1)
				(type default)
			)
			(layer "B.Fab")
		)
		(fp_line
			(start 0.12065 0.3048)
			(end 0.67945 0.3048)
			(stroke
				(width 0.1)
				(type default)
			)
			(layer "B.Fab")
		)
		(fp_line
			(start 0.12065 0.2794)
			(end 0.12065 0.3048)
			(stroke
				(width 0.1)
				(type default)
			)
			(layer "B.Fab")
		)
		(fp_line
			(start 0.12065 -0.2794)
			(end -0.12065 -0.2794)
			(stroke
				(width 0.1)
				(type default)
			)
			(layer "B.Fab")
		)
		(fp_line
			(start 0.12065 -0.305054)
			(end 0.12065 -0.2794)
			(stroke
				(width 0.1)
				(type default)
			)
			(layer "B.Fab")
		)
		(fp_line
			(start -0.120396 0.3048)
			(end -0.120396 0.2794)
			(stroke
				(width 0.1)
				(type default)
			)
			(layer "B.Fab")
		)
		(fp_line
			(start -0.120396 0.2794)
			(end 0.12065 0.2794)
			(stroke
				(width 0.1)
				(type default)
			)
			(layer "B.Fab")
		)
		(fp_line
			(start -0.12065 -0.2794)
			(end -0.12065 -0.3048)
			(stroke
				(width 0.1)
				(type default)
			)
			(layer "B.Fab")
		)
		(fp_line
			(start -0.12065 -0.3048)
			(end -0.67945 -0.3048)
			(stroke
				(width 0.1)
				(type default)
			)
			(layer "B.Fab")
		)
		(fp_line
			(start -0.67945 0.3048)
			(end -0.120396 0.3048)
			(stroke
				(width 0.1)
				(type default)
			)
			(layer "B.Fab")
		)
		(fp_line
			(start -0.67945 -0.3048)
			(end -0.67945 0.3048)
			(stroke
				(width 0.1)
				(type default)
			)
			(layer "B.Fab")
		)
		(pad "1" smd circle
			(at 0.40005 0)
			(size 0 0)
			(layers "B.Cu" "B.Mask" "B.Paste")
			(net "PVNN_TERM_CPU1")
		)
		(pad "2" smd circle
			(at -0.40005 0)
			(size 0 0)
			(layers "B.Cu" "B.Mask" "B.Paste")
			(net "SVID_CLK0_CPU1_R")
		)
	)
)
